(kicad_pcb
	(version 20260206)
	(generator "pcbnew")
	(generator_version "10.0")
	(general
		(thickness 1.6)
		(legacy_teardrops no)
	)
	(paper "A4")
	(title_block
		(title "01162023_DA0F0TEBIF0_F0T_Expander_BD_F_brd_V02_OCP.brd")
		(comment 1 "Grand Teton / footprints 9548-9554 of 9728")
	)
	(layers
		(0 "F.Cu" signal "TOP")
		(4 "In1.Cu" signal "GND")
		(6 "In2.Cu" signal "VCC")
		(8 "In3.Cu" signal "VCC1")
		(10 "In4.Cu" signal "GND1")
		(12 "In5.Cu" signal "IN1")
		(14 "In6.Cu" signal "GND2")
		(16 "In7.Cu" signal "IN2")
		(18 "In8.Cu" signal "GND3")
		(20 "In9.Cu" signal "IN3")
		(22 "In10.Cu" signal "GND4")
		(24 "In11.Cu" signal "IN4")
		(26 "In12.Cu" signal "GND5")
		(28 "In13.Cu" signal "IN5")
		(30 "In14.Cu" signal "GND6")
		(32 "In15.Cu" signal "IN6")
		(34 "In16.Cu" signal "GND7")
		(2 "B.Cu" signal "BOTTOM")
		(9 "F.Adhes" user "F.Adhesive")
		(11 "B.Adhes" user "B.Adhesive")
		(13 "F.Paste" user "Package Geometry/Pastemask Top")
		(15 "B.Paste" user "Package Geometry/Pastemask Bottom")
		(5 "F.SilkS" user "Ref Des/Silkscreen Top")
		(7 "B.SilkS" user "Ref Des/Silkscreen Bottom")
		(1 "F.Mask" user "Board Geometry/Soldermask Top")
		(3 "B.Mask" user "Board Geometry/Soldermask Bottom")
		(17 "Dwgs.User" user "User.Drawings")
		(19 "Cmts.User" user "User.Comments")
		(21 "Eco1.User" user "User.Eco1")
		(23 "Eco2.User" user "User.Eco2")
		(25 "Edge.Cuts" user "Board Geometry/Outline")
		(27 "Margin" user)
		(31 "F.CrtYd" user "Package Geometry/Place Bound Top")
		(29 "B.CrtYd" user "Package Geometry/Place Bound Bottom")
		(35 "F.Fab" user "Ref Des/Assembly Top")
		(33 "B.Fab" user "Ref Des/Assembly Bottom")
	)
	(footprint ""
		(layer "B.Cu")
		(at 377.988322 -248.203974 180)
		(property "Reference" "R970"
			(at 0 0 0)
			(layer "B.SilkS")
			(hide yes)
			(effects
				(font
					(size 1.27 1.27)
				)
				(justify mirror)
			)
		)
		(property "Value" ""
			(at 0 0 0)
			(layer "B.Fab")
			(effects
				(font
					(size 1.27 1.27)
				)
				(justify mirror)
			)
		)
		(duplicate_pad_numbers_are_jumpers no)
		(fp_line
			(start 0.7874 0.4064)
			(end 0.7874 -0.4064)
			(stroke
				(width 0.1524)
				(type default)
			)
			(layer "B.SilkS")
		)
		(fp_line
			(start 0.7874 -0.4064)
			(end -0.7874 -0.4064)
			(stroke
				(width 0.1524)
				(type default)
			)
			(layer "B.SilkS")
		)
		(fp_line
			(start -0.7874 0.4064)
			(end 0.7874 0.4064)
			(stroke
				(width 0.1524)
				(type default)
			)
			(layer "B.SilkS")
		)
		(fp_line
			(start -0.7874 -0.4064)
			(end -0.7874 0.4064)
			(stroke
				(width 0.1524)
				(type default)
			)
			(layer "B.SilkS")
		)
		(fp_line
			(start 0.67945 0.3048)
			(end 0.67945 -0.305054)
			(stroke
				(width 0.1)
				(type default)
			)
			(layer "B.Fab")
		)
		(fp_line
			(start 0.67945 -0.305054)
			(end 0.12065 -0.305054)
			(stroke
				(width 0.1)
				(type default)
			)
			(layer "B.Fab")
		)
		(fp_line
			(start 0.12065 0.3048)
			(end 0.67945 0.3048)
			(stroke
				(width 0.1)
				(type default)
			)
			(layer "B.Fab")
		)
		(fp_line
			(start 0.12065 0.2794)
			(end 0.12065 0.3048)
			(stroke
				(width 0.1)
				(type default)
			)
			(layer "B.Fab")
		)
		(fp_line
			(start 0.12065 -0.2794)
			(end -0.12065 -0.2794)
			(stroke
				(width 0.1)
				(type default)
			)
			(layer "B.Fab")
		)
		(fp_line
			(start 0.12065 -0.305054)
			(end 0.12065 -0.2794)
			(stroke
				(width 0.1)
				(type default)
			)
			(layer "B.Fab")
		)
		(fp_line
			(start -0.120396 0.3048)
			(end -0.120396 0.2794)
			(stroke
				(width 0.1)
				(type default)
			)
			(layer "B.Fab")
		)
		(fp_line
			(start -0.120396 0.2794)
			(end 0.12065 0.2794)
			(stroke
				(width 0.1)
				(type default)
			)
			(layer "B.Fab")
		)
		(fp_line
			(start -0.12065 -0.2794)
			(end -0.12065 -0.3048)
			(stroke
				(width 0.1)
				(type default)
			)
			(layer "B.Fab")
		)
		(fp_line
			(start -0.12065 -0.3048)
			(end -0.67945 -0.3048)
			(stroke
				(width 0.1)
				(type default)
			)
			(layer "B.Fab")
		)
		(fp_line
			(start -0.67945 0.3048)
			(end -0.120396 0.3048)
			(stroke
				(width 0.1)
				(type default)
			)
			(layer "B.Fab")
		)
		(fp_line
			(start -0.67945 -0.3048)
			(end -0.67945 0.3048)
			(stroke
				(width 0.1)
				(type default)
			)
			(layer "B.Fab")
		)
		(pad "1" smd circle
			(at 0.40005 0)
			(size 0 0)
			(layers "B.Cu" "B.Mask" "B.Paste")
			(net "UART_PEX3_SDB_BUF_R_TX")
		)
		(pad "2" smd circle
			(at -0.40005 0)
			(size 0 0)
			(layers "B.Cu" "B.Mask" "B.Paste")
			(net "UART_PEX3_SDB_BUF_TX")
		)
	)
	(footprint ""
		(layer "B.Cu")
		(at 344.493342 -221.98711 90)
		(property "Reference" "C2035"
			(at 0 0 90)
			(layer "B.SilkS")
			(hide yes)
			(effects
				(font
					(size 1.27 1.27)
				)
				(justify mirror)
			)
		)
		(property "Value" ""
			(at 0 0 90)
			(layer "B.Fab")
			(effects
				(font
					(size 1.27 1.27)
				)
				(justify mirror)
			)
		)
		(duplicate_pad_numbers_are_jumpers no)
		(fp_line
			(start 0.69215 -0.2921)
			(end -0.69215 -0.2921)
			(stroke
				(width 0.1524)
				(type default)
			)
			(layer "B.SilkS")
		)
		(fp_line
			(start -0.69215 -0.2921)
			(end -0.69215 0.2921)
			(stroke
				(width 0.1524)
				(type default)
			)
			(layer "B.SilkS")
		)
		(fp_line
			(start 0.69215 0.2921)
			(end 0.69215 -0.2921)
			(stroke
				(width 0.1524)
				(type default)
			)
			(layer "B.SilkS")
		)
		(fp_line
			(start -0.69215 0.2921)
			(end 0.69215 0.2921)
			(stroke
				(width 0.1524)
				(type default)
			)
			(layer "B.SilkS")
		)
		(fp_line
			(start 0.51435 -0.2794)
			(end -0.51435 -0.2794)
			(stroke
				(width 0.1)
				(type default)
			)
			(layer "B.Fab")
		)
		(fp_line
			(start -0.51435 -0.2794)
			(end -0.51435 0.2794)
			(stroke
				(width 0.1)
				(type default)
			)
			(layer "B.Fab")
		)
		(fp_line
			(start 0.51435 0.2794)
			(end 0.51435 -0.2794)
			(stroke
				(width 0.1)
				(type default)
			)
			(layer "B.Fab")
		)
		(fp_line
			(start -0.51435 0.2794)
			(end 0.51435 0.2794)
			(stroke
				(width 0.1)
				(type default)
			)
			(layer "B.Fab")
		)
		(pad "1" smd circle
			(at 0.40005 0 270)
			(size 0 0)
			(layers "B.Cu" "B.Mask" "B.Paste")
			(net "P3V3_FPGA_VCCIO0")
		)
		(pad "2" smd circle
			(at -0.40005 0 270)
			(size 0 0)
			(layers "B.Cu" "B.Mask" "B.Paste")
			(net "GND")
		)
		(zone
			(layer "B.Cu")
			(hatch none 0.5)
			(connect_pads
				(clearance 0)
			)
			(min_thickness 0.25)
			(keepout
				(tracks not_allowed)
				(vias allowed)
				(pads allowed)
				(copperpour not_allowed)
				(footprints allowed)
			)
			(placement
				(enabled no)
				(sheetname "")
			)
			(fill
				(thermal_gap 0.5)
				(thermal_bridge_width 0.5)
				(island_removal_mode 0)
			)
			(polygon
				(pts
					(xy 344.580972 -222.17761) (xy 344.639138 -222.08617) (xy 344.639138 -221.88678) (xy 344.580972 -221.79661)
					(xy 344.405712 -221.79661) (xy 344.347292 -221.88678) (xy 344.347292 -222.08617) (xy 344.405458 -222.17761)
				)
			)
		)
	)
	(footprint ""
		(layer "B.Cu")
		(at 169.574972 -305.399948 -90)
		(property "Reference" "C3151"
			(at 0 0 90)
			(layer "B.SilkS")
			(hide yes)
			(effects
				(font
					(size 1.27 1.27)
				)
				(justify mirror)
			)
		)
		(property "Value" ""
			(at 0 0 90)
			(layer "B.Fab")
			(effects
				(font
					(size 1.27 1.27)
				)
				(justify mirror)
			)
		)
		(duplicate_pad_numbers_are_jumpers no)
		(fp_line
			(start -0.299974 0.150114)
			(end 0.299974 0.150114)
			(stroke
				(width 0.1)
				(type default)
			)
			(layer "B.Fab")
		)
		(fp_line
			(start 0.299974 0.150114)
			(end 0.299974 -0.150114)
			(stroke
				(width 0.1)
				(type default)
			)
			(layer "B.Fab")
		)
		(fp_line
			(start -0.299974 -0.150114)
			(end -0.299974 0.150114)
			(stroke
				(width 0.1)
				(type default)
			)
			(layer "B.Fab")
		)
		(fp_line
			(start 0.299974 -0.150114)
			(end -0.299974 -0.150114)
			(stroke
				(width 0.1)
				(type default)
			)
			(layer "B.Fab")
		)
		(pad "1" smd rect
			(at 0.2667 0 90)
			(size 0.3048 0.381)
			(layers "B.Cu" "B.Mask" "B.Paste")
			(net "P1V25_SERDES_VDDPLL_PEX1")
		)
		(pad "2" smd rect
			(at -0.2667 0 90)
			(size 0.3048 0.381)
			(layers "B.Cu" "B.Mask" "B.Paste")
			(net "GND")
		)
	)
	(footprint ""
		(layer "B.Cu")
		(at 343.324942 -323.15531 -90)
		(property "Reference" "R6510"
			(at 0 0 90)
			(layer "B.SilkS")
			(hide yes)
			(effects
				(font
					(size 1.27 1.27)
				)
				(justify mirror)
			)
		)
		(property "Value" ""
			(at 0 0 90)
			(layer "B.Fab")
			(effects
				(font
					(size 1.27 1.27)
				)
				(justify mirror)
			)
		)
		(duplicate_pad_numbers_are_jumpers no)
		(fp_line
			(start -0.7874 0.4064)
			(end 0.7874 0.4064)
			(stroke
				(width 0.1524)
				(type default)
			)
			(layer "B.SilkS")
		)
		(fp_line
			(start 0.7874 0.4064)
			(end 0.7874 -0.4064)
			(stroke
				(width 0.1524)
				(type default)
			)
			(layer "B.SilkS")
		)
		(fp_line
			(start -0.7874 -0.4064)
			(end -0.7874 0.4064)
			(stroke
				(width 0.1524)
				(type default)
			)
			(layer "B.SilkS")
		)
		(fp_line
			(start 0.7874 -0.4064)
			(end -0.7874 -0.4064)
			(stroke
				(width 0.1524)
				(type default)
			)
			(layer "B.SilkS")
		)
		(fp_line
			(start -0.67945 0.3048)
			(end -0.120396 0.3048)
			(stroke
				(width 0.1)
				(type default)
			)
			(layer "B.Fab")
		)
		(fp_line
			(start -0.120396 0.3048)
			(end -0.120396 0.2794)
			(stroke
				(width 0.1)
				(type default)
			)
			(layer "B.Fab")
		)
		(fp_line
			(start 0.12065 0.3048)
			(end 0.67945 0.3048)
			(stroke
				(width 0.1)
				(type default)
			)
			(layer "B.Fab")
		)
		(fp_line
			(start 0.67945 0.3048)
			(end 0.67945 -0.305054)
			(stroke
				(width 0.1)
				(type default)
			)
			(layer "B.Fab")
		)
		(fp_line
			(start -0.120396 0.2794)
			(end 0.12065 0.2794)
			(stroke
				(width 0.1)
				(type default)
			)
			(layer "B.Fab")
		)
		(fp_line
			(start 0.12065 0.2794)
			(end 0.12065 0.3048)
			(stroke
				(width 0.1)
				(type default)
			)
			(layer "B.Fab")
		)
		(fp_line
			(start -0.12065 -0.2794)
			(end -0.12065 -0.3048)
			(stroke
				(width 0.1)
				(type default)
			)
			(layer "B.Fab")
		)
		(fp_line
			(start 0.12065 -0.2794)
			(end -0.12065 -0.2794)
			(stroke
				(width 0.1)
				(type default)
			)
			(layer "B.Fab")
		)
		(fp_line
			(start -0.67945 -0.3048)
			(end -0.67945 0.3048)
			(stroke
				(width 0.1)
				(type default)
			)
			(layer "B.Fab")
		)
		(fp_line
			(start -0.12065 -0.3048)
			(end -0.67945 -0.3048)
			(stroke
				(width 0.1)
				(type default)
			)
			(layer "B.Fab")
		)
		(fp_line
			(start 0.12065 -0.305054)
			(end 0.12065 -0.2794)
			(stroke
				(width 0.1)
				(type default)
			)
			(layer "B.Fab")
		)
		(fp_line
			(start 0.67945 -0.305054)
			(end 0.12065 -0.305054)
			(stroke
				(width 0.1)
				(type default)
			)
			(layer "B.Fab")
		)
		(pad "1" smd circle
			(at 0.40005 0 90)
			(size 0 0)
			(layers "B.Cu" "B.Mask" "B.Paste")
			(net "P0V8_SERDES_VDDA_PEX2")
		)
		(pad "2" smd circle
			(at -0.40005 0 90)
			(size 0 0)
			(layers "B.Cu" "B.Mask" "B.Paste")
			(net "P0V8_SERDES_VDDA_PEX2_C5")
		)
	)
	(footprint ""
		(layer "B.Cu")
		(at 344.784172 -277.644352 180)
		(property "Reference" "PC6615"
			(at 0 0 0)
			(layer "B.SilkS")
			(hide yes)
			(effects
				(font
					(size 1.27 1.27)
				)
				(justify mirror)
			)
		)
		(property "Value" ""
			(at 0 0 0)
			(layer "B.Fab")
			(effects
				(font
					(size 1.27 1.27)
				)
				(justify mirror)
			)
		)
		(duplicate_pad_numbers_are_jumpers no)
		(fp_line
			(start 1.524 0.762)
			(end 1.524 -0.762)
			(stroke
				(width 0.1524)
				(type default)
			)
			(layer "B.SilkS")
		)
		(fp_line
			(start 1.524 -0.762)
			(end -1.524 -0.762)
			(stroke
				(width 0.1524)
				(type default)
			)
			(layer "B.SilkS")
		)
		(fp_line
			(start -1.524 0.762)
			(end 1.524 0.762)
			(stroke
				(width 0.1524)
				(type default)
			)
			(layer "B.SilkS")
		)
		(fp_line
			(start -1.524 -0.762)
			(end -1.524 0.762)
			(stroke
				(width 0.1524)
				(type default)
			)
			(layer "B.SilkS")
		)
		(fp_line
			(start 1.1049 0.724916)
			(end -1.1049 0.724916)
			(stroke
				(width 0.1)
				(type default)
			)
			(layer "B.Fab")
		)
		(fp_line
			(start 1.1049 -0.724916)
			(end 1.1049 0.724916)
			(stroke
				(width 0.1)
				(type default)
			)
			(layer "B.Fab")
		)
		(fp_line
			(start -1.1049 0.724916)
			(end -1.1049 -0.724916)
			(stroke
				(width 0.1)
				(type default)
			)
			(layer "B.Fab")
		)
		(fp_line
			(start -1.1049 -0.724916)
			(end 1.1049 -0.724916)
			(stroke
				(width 0.1)
				(type default)
			)
			(layer "B.Fab")
		)
		(pad "1" smd rect
			(at 0.889 0 180)
			(size 1.016 1.27)
			(layers "B.Cu" "B.Mask" "B.Paste")
			(net "SW_P12V_P0V8_PEX2_FLT")
		)
		(pad "2" smd rect
			(at -0.889 0 180)
			(size 1.016 1.27)
			(layers "B.Cu" "B.Mask" "B.Paste")
			(net "GND")
		)
	)
	(footprint ""
		(layer "B.Cu")
		(at 449.83781 -279.694386)
		(property "Reference" "C4388"
			(at 0 0 0)
			(layer "B.SilkS")
			(hide yes)
			(effects
				(font
					(size 1.27 1.27)
				)
				(justify mirror)
			)
		)
		(property "Value" ""
			(at 0 0 0)
			(layer "B.Fab")
			(effects
				(font
					(size 1.27 1.27)
				)
				(justify mirror)
			)
		)
		(duplicate_pad_numbers_are_jumpers no)
		(fp_line
			(start -1.2954 -0.5842)
			(end -1.2954 0.5842)
			(stroke
				(width 0.1524)
				(type default)
			)
			(layer "B.SilkS")
		)
		(fp_line
			(start -1.2954 0.5842)
			(end 1.2954 0.5842)
			(stroke
				(width 0.1524)
				(type default)
			)
			(layer "B.SilkS")
		)
		(fp_line
			(start 1.2954 -0.5842)
			(end -1.2954 -0.5842)
			(stroke
				(width 0.1524)
				(type default)
			)
			(layer "B.SilkS")
		)
		(fp_line
			(start 1.2954 0.5842)
			(end 1.2954 -0.5842)
			(stroke
				(width 0.1524)
				(type default)
			)
			(layer "B.SilkS")
		)
		(fp_line
			(start -1.1938 -0.4064)
			(end -1.1938 0.4064)
			(stroke
				(width 0.1)
				(type default)
			)
			(layer "B.Fab")
		)
		(fp_line
			(start -1.1938 0.4064)
			(end -0.8636 0.4064)
			(stroke
				(width 0.1)
				(type default)
			)
			(layer "B.Fab")
		)
		(fp_line
			(start -0.8636 -0.4572)
			(end -0.8636 -0.4064)
			(stroke
				(width 0.1)
				(type default)
			)
			(layer "B.Fab")
		)
		(fp_line
			(start -0.8636 -0.4064)
			(end -1.1938 -0.4064)
			(stroke
				(width 0.1)
				(type default)
			)
			(layer "B.Fab")
		)
		(fp_line
			(start -0.8636 0.4064)
			(end -0.8636 0.4572)
			(stroke
				(width 0.1)
				(type default)
			)
			(layer "B.Fab")
		)
		(fp_line
			(start -0.8636 0.4572)
			(end 0.8636 0.4572)
			(stroke
				(width 0.1)
				(type default)
			)
			(layer "B.Fab")
		)
		(fp_line
			(start 0.8636 -0.4572)
			(end -0.8636 -0.4572)
			(stroke
				(width 0.1)
				(type default)
			)
			(layer "B.Fab")
		)
		(fp_line
			(start 0.8636 -0.4064)
			(end 0.8636 -0.4572)
			(stroke
				(width 0.1)
				(type default)
			)
			(layer "B.Fab")
		)
		(fp_line
			(start 0.8636 0.4064)
			(end 1.1938 0.4064)
			(stroke
				(width 0.1)
				(type default)
			)
			(layer "B.Fab")
		)
		(fp_line
			(start 0.8636 0.4572)
			(end 0.8636 0.4064)
			(stroke
				(width 0.1)
				(type default)
			)
			(layer "B.Fab")
		)
		(fp_line
			(start 1.1938 -0.4064)
			(end 0.8636 -0.4064)
			(stroke
				(width 0.1)
				(type default)
			)
			(layer "B.Fab")
		)
		(fp_line
			(start 1.1938 0.4064)
			(end 1.1938 -0.4064)
			(stroke
				(width 0.1)
				(type default)
			)
			(layer "B.Fab")
		)
		(pad "1" smd rect
			(at 0.7366 0 270)
			(size 0.7112 0.8128)
			(layers "B.Cu" "B.Mask" "B.Paste")
			(net "P1V25_PEX3")
		)
		(pad "2" smd rect
			(at -0.7366 0 270)
			(size 0.7112 0.8128)
			(layers "B.Cu" "B.Mask" "B.Paste")
			(net "GND")
		)
	)
	(footprint ""
		(layer "B.Cu")
		(at 361.913424 -308.613556 90)
		(property "Reference" "C4358"
			(at 0 0 90)
			(layer "B.SilkS")
			(hide yes)
			(effects
				(font
					(size 1.27 1.27)
				)
				(justify mirror)
			)
		)
		(property "Value" ""
			(at 0 0 90)
			(layer "B.Fab")
			(effects
				(font
					(size 1.27 1.27)
				)
				(justify mirror)
			)
		)
		(duplicate_pad_numbers_are_jumpers no)
		(fp_line
			(start 1.2954 -0.5842)
			(end -1.2954 -0.5842)
			(stroke
				(width 0.1524)
				(type default)
			)
			(layer "B.SilkS")
		)
		(fp_line
			(start -1.2954 -0.5842)
			(end -1.2954 0.5842)
			(stroke
				(width 0.1524)
				(type default)
			)
			(layer "B.SilkS")
		)
		(fp_line
			(start 1.2954 0.5842)
			(end 1.2954 -0.5842)
			(stroke
				(width 0.1524)
				(type default)
			)
			(layer "B.SilkS")
		)
		(fp_line
			(start -1.2954 0.5842)
			(end 1.2954 0.5842)
			(stroke
				(width 0.1524)
				(type default)
			)
			(layer "B.SilkS")
		)
		(fp_line
			(start 0.8636 -0.4572)
			(end -0.8636 -0.4572)
			(stroke
				(width 0.1)
				(type default)
			)
			(layer "B.Fab")
		)
		(fp_line
			(start -0.8636 -0.4572)
			(end -0.8636 -0.4064)
			(stroke
				(width 0.1)
				(type default)
			)
			(layer "B.Fab")
		)
		(fp_line
			(start 1.1938 -0.4064)
			(end 0.8636 -0.4064)
			(stroke
				(width 0.1)
				(type default)
			)
			(layer "B.Fab")
		)
		(fp_line
			(start 0.8636 -0.4064)
			(end 0.8636 -0.4572)
			(stroke
				(width 0.1)
				(type default)
			)
			(layer "B.Fab")
		)
		(fp_line
			(start -0.8636 -0.4064)
			(end -1.1938 -0.4064)
			(stroke
				(width 0.1)
				(type default)
			)
			(layer "B.Fab")
		)
		(fp_line
			(start -1.1938 -0.4064)
			(end -1.1938 0.4064)
			(stroke
				(width 0.1)
				(type default)
			)
			(layer "B.Fab")
		)
		(fp_line
			(start 1.1938 0.4064)
			(end 1.1938 -0.4064)
			(stroke
				(width 0.1)
				(type default)
			)
			(layer "B.Fab")
		)
		(fp_line
			(start 0.8636 0.4064)
			(end 1.1938 0.4064)
			(stroke
				(width 0.1)
				(type default)
			)
			(layer "B.Fab")
		)
		(fp_line
			(start -0.8636 0.4064)
			(end -0.8636 0.4572)
			(stroke
				(width 0.1)
				(type default)
			)
			(layer "B.Fab")
		)
		(fp_line
			(start -1.1938 0.4064)
			(end -0.8636 0.4064)
			(stroke
				(width 0.1)
				(type default)
			)
			(layer "B.Fab")
		)
		(fp_line
			(start 0.8636 0.4572)
			(end 0.8636 0.4064)
			(stroke
				(width 0.1)
				(type default)
			)
			(layer "B.Fab")
		)
		(fp_line
			(start -0.8636 0.4572)
			(end 0.8636 0.4572)
			(stroke
				(width 0.1)
				(type default)
			)
			(layer "B.Fab")
		)
		(pad "1" smd rect
			(at 0.7366 0)
			(size 0.7112 0.8128)
			(layers "B.Cu" "B.Mask" "B.Paste")
			(net "P0V8_PEX3")
		)
		(pad "2" smd rect
			(at -0.7366 0)
			(size 0.7112 0.8128)
			(layers "B.Cu" "B.Mask" "B.Paste")
			(net "GND")
		)
	)
)
